(kicad_pcb
	(version 20260206)
	(generator "pcbnew")
	(generator_version "10.0")
	(general
		(thickness 1.6)
		(legacy_teardrops no)
	)
	(paper "A4")
	(title_block
		(title "Bryce Canyon_F.DPB_16315-1-OCP.brd")
		(comment 1 "Bryce Canyon / footprints 1545-1551 of 2223")
	)
	(layers
		(0 "F.Cu" signal "TOP")
		(4 "In1.Cu" signal "L2GND")
		(6 "In2.Cu" signal "L3")
		(8 "In3.Cu" signal "L4GND")
		(10 "In4.Cu" signal "L5")
		(12 "In5.Cu" signal "L6VCC")
		(14 "In6.Cu" signal "L7VCC")
		(16 "In7.Cu" signal "L8")
		(18 "In8.Cu" signal "L9GND")
		(20 "In9.Cu" signal "L10")
		(22 "In10.Cu" signal "L11GND")
		(2 "B.Cu" signal "BOTTOM")
		(9 "F.Adhes" user "F.Adhesive")
		(11 "B.Adhes" user "B.Adhesive")
		(13 "F.Paste" user "Package Geometry/Pastemask Top")
		(15 "B.Paste" user "Package Geometry/Pastemask Bottom")
		(5 "F.SilkS" user "Ref Des/Silkscreen Top")
		(7 "B.SilkS" user "Ref Des/Silkscreen Bottom")
		(1 "F.Mask" user "Board Geometry/Soldermask Top")
		(3 "B.Mask" user "Board Geometry/Soldermask Bottom")
		(17 "Dwgs.User" user "User.Drawings")
		(19 "Cmts.User" user "User.Comments")
		(21 "Eco1.User" user "User.Eco1")
		(23 "Eco2.User" user "User.Eco2")
		(25 "Edge.Cuts" user "Board Geometry/Outline")
		(27 "Margin" user)
		(31 "F.CrtYd" user "Package Geometry/Place Bound Top")
		(29 "B.CrtYd" user "Package Geometry/Place Bound Bottom")
		(35 "F.Fab" user "Ref Des/Assembly Top")
		(33 "B.Fab" user "Ref Des/Assembly Bottom")
	)
	(footprint ""
		(layer "F.Cu")
		(at 267.822426 -211.824062 180)
		(property "Reference" "R603"
			(at 0 0 180)
			(layer "F.SilkS")
			(hide yes)
			(effects
				(font
					(size 1.27 1.27)
				)
			)
		)
		(property "Value" "2K2R2F-GP"
			(at 0.064008 -3.993896 180)
			(unlocked yes)
			(layer "F.Fab")
			(hide yes)
			(effects
				(font
					(size 1.016 1.016)
					(thickness 0.1524)
				)
			)
		)
		(property "Device Type" "R402H16"
			(at 0.064008 -5.517896 180)
			(unlocked yes)
			(layer "F.Fab")
			(hide yes)
			(effects
				(font
					(size 1.016 1.016)
					(thickness 0.1524)
				)
			)
		)
		(duplicate_pad_numbers_are_jumpers no)
		(fp_line
			(start 0.508 -0.9398)
			(end -0.508 -0.9398)
			(stroke
				(width 0.1524)
				(type default)
			)
			(layer "F.SilkS")
		)
		(fp_line
			(start -0.508 -0.9398)
			(end -0.508 0.9398)
			(stroke
				(width 0.1524)
				(type default)
			)
			(layer "F.SilkS")
		)
		(fp_rect
			(start -0.508 0.9398)
			(end 0.508 -0.9398)
			(stroke
				(width 0)
				(type default)
			)
			(fill no)
			(layer "F.CrtYd")
		)
		(fp_rect
			(start -0.508 0.9398)
			(end 0.508 -0.9398)
			(stroke
				(width 0)
				(type default)
			)
			(fill no)
			(layer "F.Fab")
		)
		(pad "1" smd custom
			(at 0 -0.4445 180)
			(size 0.1397 0.1397)
			(layers "F.Cu" "F.Mask" "F.Paste")
			(net "P3V3_STBY_A")
			(options
				(clearance outline)
				(anchor circle)
			)
			(primitives
				(gr_poly
					(pts
						(arc
							(start -0.1778 -0.2794)
							(mid -0.249642 -0.249642)
							(end -0.2794 -0.1778)
						)
						(arc
							(start -0.2794 0.1778)
							(mid -0.249642 0.249642)
							(end -0.1778 0.2794)
						)
						(arc
							(start 0.1778 0.2794)
							(mid 0.249642 0.249642)
							(end 0.2794 0.1778)
						)
						(arc
							(start 0.2794 -0.1778)
							(mid 0.249642 -0.249642)
							(end 0.1778 -0.2794)
						)
					)
					(width 0)
					(fill yes)
				)
			)
		)
		(pad "2" smd custom
			(at 0 0.4445 180)
			(size 0.1397 0.1397)
			(layers "F.Cu" "F.Mask" "F.Paste")
			(net "I2C_DPB_A_SCL")
			(options
				(clearance outline)
				(anchor circle)
			)
			(primitives
				(gr_poly
					(pts
						(arc
							(start -0.1778 -0.2794)
							(mid -0.249642 -0.249642)
							(end -0.2794 -0.1778)
						)
						(arc
							(start -0.2794 0.1778)
							(mid -0.249642 0.249642)
							(end -0.1778 0.2794)
						)
						(arc
							(start 0.1778 0.2794)
							(mid 0.249642 0.249642)
							(end 0.2794 0.1778)
						)
						(arc
							(start 0.2794 -0.1778)
							(mid 0.249642 -0.249642)
							(end 0.1778 -0.2794)
						)
					)
					(width 0)
					(fill yes)
				)
			)
		)
	)
	(footprint ""
		(layer "F.Cu")
		(at 115.080796 -48.554894 180)
		(property "Reference" "Q163"
			(at 0 0 180)
			(layer "F.SilkS")
			(hide yes)
			(effects
				(font
					(size 1.27 1.27)
				)
			)
		)
		(property "Value" "2N7002KDW-GP"
			(at -2.3622 -8.2042 180)
			(unlocked yes)
			(layer "F.Fab")
			(hide yes)
			(effects
				(font
					(size 1.016 1.016)
					(thickness 0.1524)
				)
			)
		)
		(property "Device Type" "SOT-363H44"
			(at -2.3622 -10.1092 180)
			(unlocked yes)
			(layer "F.Fab")
			(hide yes)
			(effects
				(font
					(size 1.016 1.016)
					(thickness 0.1524)
				)
			)
		)
		(duplicate_pad_numbers_are_jumpers no)
		(fp_line
			(start 1.4478 1.7018)
			(end 1.4478 -1.7018)
			(stroke
				(width 0.1524)
				(type default)
			)
			(layer "F.SilkS")
		)
		(fp_line
			(start 1.4478 -1.7018)
			(end -1.4478 -1.7018)
			(stroke
				(width 0.1524)
				(type default)
			)
			(layer "F.SilkS")
		)
		(fp_line
			(start -1.27 1.524)
			(end -1.27 0.6604)
			(stroke
				(width 0.4826)
				(type default)
			)
			(layer "F.SilkS")
		)
		(fp_line
			(start -1.4478 1.7018)
			(end 1.4478 1.7018)
			(stroke
				(width 0.1524)
				(type default)
			)
			(layer "F.SilkS")
		)
		(fp_line
			(start -1.4478 -1.7018)
			(end -1.4478 1.7018)
			(stroke
				(width 0.1524)
				(type default)
			)
			(layer "F.SilkS")
		)
		(fp_poly
			(pts
				(xy -1.524 -1.778) (xy 1.524 -1.778) (xy 1.524 1.778) (xy -1.524 1.778)
			)
			(stroke
				(width 0)
				(type default)
			)
			(fill no)
			(layer "F.CrtYd")
		)
		(fp_poly
			(pts
				(xy -1.524 -1.778) (xy 1.524 -1.778) (xy 1.524 1.778) (xy -1.524 1.778)
			)
			(stroke
				(width 0)
				(type default)
			)
			(fill no)
			(layer "F.Fab")
		)
		(pad "1" smd rect
			(at -0.65024 0.9398 180)
			(size 0.4064 1.016)
			(layers "F.Cu" "F.Mask" "F.Paste")
			(net "GND")
		)
		(pad "2" smd rect
			(at 0 0.9398 180)
			(size 0.4064 1.016)
			(layers "F.Cu" "F.Mask" "F.Paste")
			(net "SW_PWR_R_HDD27")
		)
		(pad "3" smd rect
			(at 0.65024 0.9398 180)
			(size 0.4064 1.016)
			(layers "F.Cu" "F.Mask" "F.Paste")
			(net "SW_HDD_P27")
		)
		(pad "4" smd rect
			(at 0.65024 -0.9398 180)
			(size 0.4064 1.016)
			(layers "F.Cu" "F.Mask" "F.Paste")
			(net "GND")
		)
		(pad "5" smd rect
			(at 0 -0.9398 180)
			(size 0.4064 1.016)
			(layers "F.Cu" "F.Mask" "F.Paste")
			(net "SW_HDD_G27")
		)
		(pad "6" smd rect
			(at -0.65024 -0.9398 180)
			(size 0.4064 1.016)
			(layers "F.Cu" "F.Mask" "F.Paste")
			(net "SW_HDD_R27")
		)
	)
	(footprint ""
		(layer "F.Cu")
		(at 64.013334 -159.219392 90)
		(property "Reference" "C207"
			(at 0 0 90)
			(layer "F.SilkS")
			(hide yes)
			(effects
				(font
					(size 1.27 1.27)
				)
			)
		)
		(property "Value" "SCD01U16V1KX-GP"
			(at -2.8321 -1.7399 90)
			(unlocked yes)
			(layer "F.Fab")
			(hide yes)
			(effects
				(font
					(size 1.016 1.016)
					(thickness 0.1524)
				)
			)
		)
		(property "Device Type" "C0201H13"
			(at -2.8321 -3.2639 90)
			(unlocked yes)
			(layer "F.Fab")
			(hide yes)
			(effects
				(font
					(size 1.016 1.016)
					(thickness 0.1524)
				)
			)
		)
		(duplicate_pad_numbers_are_jumpers no)
		(fp_rect
			(start -0.2794 0.6477)
			(end 0.2794 -0.6477)
			(stroke
				(width 0)
				(type default)
			)
			(fill no)
			(layer "F.CrtYd")
		)
		(fp_rect
			(start -0.2794 0.6477)
			(end 0.2794 -0.6477)
			(stroke
				(width 0)
				(type default)
			)
			(fill no)
			(layer "F.Fab")
		)
		(pad "1" smd custom
			(at 0 -0.2794 90)
			(size 0.0762 0.0762)
			(layers "F.Cu" "F.Mask" "F.Paste")
			(net "SAS_HDD_RX_N13")
			(options
				(clearance outline)
				(anchor circle)
			)
			(primitives
				(gr_poly
					(pts
						(arc
							(start 0.1524 -0.127)
							(mid 0.137521 -0.162921)
							(end 0.1016 -0.1778)
						)
						(arc
							(start -0.1016 -0.1778)
							(mid -0.137521 -0.162921)
							(end -0.1524 -0.127)
						)
						(arc
							(start -0.1524 0.127)
							(mid -0.137521 0.162921)
							(end -0.1016 0.1778)
						)
						(arc
							(start 0.1016 0.1778)
							(mid 0.137521 0.162921)
							(end 0.1524 0.127)
						)
					)
					(width 0)
					(fill yes)
				)
			)
		)
		(pad "2" smd custom
			(at 0 0.2794 90)
			(size 0.0762 0.0762)
			(layers "F.Cu" "F.Mask" "F.Paste")
			(net "PHY_SCC_A_TO_DRV_A_13_DN")
			(options
				(clearance outline)
				(anchor circle)
			)
			(primitives
				(gr_poly
					(pts
						(arc
							(start 0.1524 -0.127)
							(mid 0.137521 -0.162921)
							(end 0.1016 -0.1778)
						)
						(arc
							(start -0.1016 -0.1778)
							(mid -0.137521 -0.162921)
							(end -0.1524 -0.127)
						)
						(arc
							(start -0.1524 0.127)
							(mid -0.137521 0.162921)
							(end -0.1016 0.1778)
						)
						(arc
							(start 0.1016 0.1778)
							(mid 0.137521 0.162921)
							(end 0.1524 0.127)
						)
					)
					(width 0)
					(fill yes)
				)
			)
		)
	)
	(footprint ""
		(layer "F.Cu")
		(at 23.936198 -71.287894)
		(property "Reference" "C357"
			(at 0 0 0)
			(layer "F.SilkS")
			(hide yes)
			(effects
				(font
					(size 1.27 1.27)
				)
			)
		)
		(property "Value" "SC4D7U25V5KX-1-GP"
			(at -0.0762 -6.1214 0)
			(unlocked yes)
			(layer "F.Fab")
			(hide yes)
			(effects
				(font
					(size 1.016 1.016)
					(thickness 0.1524)
				)
			)
		)
		(property "Device Type" "C805H58"
			(at -0.0762 -8.1534 0)
			(unlocked yes)
			(layer "F.Fab")
			(hide yes)
			(effects
				(font
					(size 1.016 1.016)
					(thickness 0.1524)
				)
			)
		)
		(duplicate_pad_numbers_are_jumpers no)
		(fp_line
			(start 0.635 0)
			(end -0.635 0)
			(stroke
				(width 0.508)
				(type default)
			)
			(layer "F.SilkS")
		)
		(fp_rect
			(start -0.9652 1.778)
			(end 0.9652 -1.778)
			(stroke
				(width 0)
				(type default)
			)
			(fill no)
			(layer "F.CrtYd")
		)
		(fp_poly
			(pts
				(xy -0.9652 -1.778) (xy 0.9652 -1.778) (xy 0.9652 1.778) (xy -0.9652 1.778)
			)
			(stroke
				(width 0)
				(type default)
			)
			(fill no)
			(layer "F.Fab")
		)
		(pad "1" smd rect
			(at 0 -0.9652)
			(size 1.397 1.143)
			(layers "F.Cu" "F.Mask" "F.Paste")
			(net "P12V_HDD24")
		)
		(pad "2" smd rect
			(at 0 0.9652)
			(size 1.397 1.143)
			(layers "F.Cu" "F.Mask" "F.Paste")
			(net "GND")
		)
	)
	(footprint ""
		(layer "F.Cu")
		(at 26.381202 -254.84455 -90)
		(property "Reference" "R1218"
			(at 0 0 270)
			(layer "F.SilkS")
			(hide yes)
			(effects
				(font
					(size 1.27 1.27)
				)
			)
		)
		(property "Value" "143KR2F-L-1-GP"
			(at 0.064008 -3.993896 270)
			(unlocked yes)
			(layer "F.Fab")
			(hide yes)
			(effects
				(font
					(size 1.016 1.016)
					(thickness 0.1524)
				)
			)
		)
		(property "Device Type" "R402H16"
			(at 0.064008 -5.517896 270)
			(unlocked yes)
			(layer "F.Fab")
			(hide yes)
			(effects
				(font
					(size 1.016 1.016)
					(thickness 0.1524)
				)
			)
		)
		(duplicate_pad_numbers_are_jumpers no)
		(fp_line
			(start -0.508 -0.9398)
			(end -0.508 0.9398)
			(stroke
				(width 0.1524)
				(type default)
			)
			(layer "F.SilkS")
		)
		(fp_line
			(start 0.508 -0.9398)
			(end -0.508 -0.9398)
			(stroke
				(width 0.1524)
				(type default)
			)
			(layer "F.SilkS")
		)
		(fp_rect
			(start -0.508 0.9398)
			(end 0.508 -0.9398)
			(stroke
				(width 0)
				(type default)
			)
			(fill no)
			(layer "F.CrtYd")
		)
		(fp_rect
			(start -0.508 0.9398)
			(end 0.508 -0.9398)
			(stroke
				(width 0)
				(type default)
			)
			(fill no)
			(layer "F.Fab")
		)
		(pad "1" smd custom
			(at 0 -0.4445 270)
			(size 0.1397 0.1397)
			(layers "F.Cu" "F.Mask" "F.Paste")
			(net "AGND_P5V_A")
			(options
				(clearance outline)
				(anchor circle)
			)
			(primitives
				(gr_poly
					(pts
						(arc
							(start -0.1778 -0.2794)
							(mid -0.249642 -0.249642)
							(end -0.2794 -0.1778)
						)
						(arc
							(start -0.2794 0.1778)
							(mid -0.249642 0.249642)
							(end -0.1778 0.2794)
						)
						(arc
							(start 0.1778 0.2794)
							(mid 0.249642 0.249642)
							(end 0.2794 0.1778)
						)
						(arc
							(start 0.2794 -0.1778)
							(mid 0.249642 -0.249642)
							(end 0.1778 -0.2794)
						)
					)
					(width 0)
					(fill yes)
				)
			)
		)
		(pad "2" smd custom
			(at 0 0.4445 270)
			(size 0.1397 0.1397)
			(layers "F.Cu" "F.Mask" "F.Paste")
			(net "P5V_A_TRIP")
			(options
				(clearance outline)
				(anchor circle)
			)
			(primitives
				(gr_poly
					(pts
						(arc
							(start -0.1778 -0.2794)
							(mid -0.249642 -0.249642)
							(end -0.2794 -0.1778)
						)
						(arc
							(start -0.2794 0.1778)
							(mid -0.249642 0.249642)
							(end -0.1778 0.2794)
						)
						(arc
							(start 0.1778 0.2794)
							(mid 0.249642 0.249642)
							(end 0.2794 0.1778)
						)
						(arc
							(start 0.2794 -0.1778)
							(mid 0.249642 -0.249642)
							(end 0.1778 -0.2794)
						)
					)
					(width 0)
					(fill yes)
				)
			)
		)
	)
	(footprint ""
		(layer "F.Cu")
		(at 130.2385 -130.269996 -90)
		(property "Reference" "R518"
			(at 0 0 270)
			(layer "F.SilkS")
			(hide yes)
			(effects
				(font
					(size 1.27 1.27)
				)
			)
		)
		(property "Value" "4K7R2J-2-GP"
			(at 0.064008 -3.993896 270)
			(unlocked yes)
			(layer "F.Fab")
			(hide yes)
			(effects
				(font
					(size 1.016 1.016)
					(thickness 0.1524)
				)
			)
		)
		(property "Device Type" "R402H16"
			(at 0.064008 -5.517896 270)
			(unlocked yes)
			(layer "F.Fab")
			(hide yes)
			(effects
				(font
					(size 1.016 1.016)
					(thickness 0.1524)
				)
			)
		)
		(duplicate_pad_numbers_are_jumpers no)
		(fp_line
			(start -0.508 -0.9398)
			(end -0.508 0.9398)
			(stroke
				(width 0.1524)
				(type default)
			)
			(layer "F.SilkS")
		)
		(fp_line
			(start 0.508 -0.9398)
			(end -0.508 -0.9398)
			(stroke
				(width 0.1524)
				(type default)
			)
			(layer "F.SilkS")
		)
		(fp_rect
			(start -0.508 0.9398)
			(end 0.508 -0.9398)
			(stroke
				(width 0)
				(type default)
			)
			(fill no)
			(layer "F.CrtYd")
		)
		(fp_rect
			(start -0.508 0.9398)
			(end 0.508 -0.9398)
			(stroke
				(width 0)
				(type default)
			)
			(fill no)
			(layer "F.Fab")
		)
		(pad "1" smd custom
			(at 0 -0.4445 270)
			(size 0.1397 0.1397)
			(layers "F.Cu" "F.Mask" "F.Paste")
			(net "DRIVE_A_16_ACT")
			(options
				(clearance outline)
				(anchor circle)
			)
			(primitives
				(gr_poly
					(pts
						(arc
							(start -0.1778 -0.2794)
							(mid -0.249642 -0.249642)
							(end -0.2794 -0.1778)
						)
						(arc
							(start -0.2794 0.1778)
							(mid -0.249642 0.249642)
							(end -0.1778 0.2794)
						)
						(arc
							(start 0.1778 0.2794)
							(mid 0.249642 0.249642)
							(end 0.2794 0.1778)
						)
						(arc
							(start 0.2794 -0.1778)
							(mid 0.249642 -0.249642)
							(end 0.1778 -0.2794)
						)
					)
					(width 0)
					(fill yes)
				)
			)
		)
		(pad "2" smd custom
			(at 0 0.4445 270)
			(size 0.1397 0.1397)
			(layers "F.Cu" "F.Mask" "F.Paste")
			(net "GND")
			(options
				(clearance outline)
				(anchor circle)
			)
			(primitives
				(gr_poly
					(pts
						(arc
							(start -0.1778 -0.2794)
							(mid -0.249642 -0.249642)
							(end -0.2794 -0.1778)
						)
						(arc
							(start -0.2794 0.1778)
							(mid -0.249642 0.249642)
							(end -0.1778 0.2794)
						)
						(arc
							(start 0.1778 0.2794)
							(mid 0.249642 0.249642)
							(end 0.2794 0.1778)
						)
						(arc
							(start 0.2794 -0.1778)
							(mid 0.249642 -0.249642)
							(end 0.1778 -0.2794)
						)
					)
					(width 0)
					(fill yes)
				)
			)
		)
	)
	(footprint ""
		(layer "F.Cu")
		(at 430.387252 -45.735494 180)
		(property "Reference" "R906"
			(at 0 0 180)
			(layer "F.SilkS")
			(hide yes)
			(effects
				(font
					(size 1.27 1.27)
				)
			)
		)
		(property "Value" "0R2J-2-GP"
			(at 0.064008 -3.993896 180)
			(unlocked yes)
			(layer "F.Fab")
			(hide yes)
			(effects
				(font
					(size 1.016 1.016)
					(thickness 0.1524)
				)
			)
		)
		(property "Device Type" "R402H16"
			(at 0.064008 -5.517896 180)
			(unlocked yes)
			(layer "F.Fab")
			(hide yes)
			(effects
				(font
					(size 1.016 1.016)
					(thickness 0.1524)
				)
			)
		)
		(duplicate_pad_numbers_are_jumpers no)
		(fp_line
			(start 0.508 -0.9398)
			(end -0.508 -0.9398)
			(stroke
				(width 0.1524)
				(type default)
			)
			(layer "F.SilkS")
		)
		(fp_line
			(start -0.508 -0.9398)
			(end -0.508 0.9398)
			(stroke
				(width 0.1524)
				(type default)
			)
			(layer "F.SilkS")
		)
		(fp_rect
			(start -0.508 0.9398)
			(end 0.508 -0.9398)
			(stroke
				(width 0)
				(type default)
			)
			(fill no)
			(layer "F.CrtYd")
		)
		(fp_rect
			(start -0.508 0.9398)
			(end 0.508 -0.9398)
			(stroke
				(width 0)
				(type default)
			)
			(fill no)
			(layer "F.Fab")
		)
		(pad "1" smd custom
			(at 0 -0.4445 180)
			(size 0.1397 0.1397)
			(layers "F.Cu" "F.Mask" "F.Paste")
			(net "SW_HDD_G33")
			(options
				(clearance outline)
				(anchor circle)
			)
			(primitives
				(gr_poly
					(pts
						(arc
							(start -0.1778 -0.2794)
							(mid -0.249642 -0.249642)
							(end -0.2794 -0.1778)
						)
						(arc
							(start -0.2794 0.1778)
							(mid -0.249642 0.249642)
							(end -0.1778 0.2794)
						)
						(arc
							(start 0.1778 0.2794)
							(mid 0.249642 0.249642)
							(end 0.2794 0.1778)
						)
						(arc
							(start 0.2794 -0.1778)
							(mid 0.249642 -0.249642)
							(end 0.1778 -0.2794)
						)
					)
					(width 0)
					(fill yes)
				)
			)
		)
		(pad "2" smd custom
			(at 0 0.4445 180)
			(size 0.1397 0.1397)
			(layers "F.Cu" "F.Mask" "F.Paste")
			(net "SW_HDD_R33")
			(options
				(clearance outline)
				(anchor circle)
			)
			(primitives
				(gr_poly
					(pts
						(arc
							(start -0.1778 -0.2794)
							(mid -0.249642 -0.249642)
							(end -0.2794 -0.1778)
						)
						(arc
							(start -0.2794 0.1778)
							(mid -0.249642 0.249642)
							(end -0.1778 0.2794)
						)
						(arc
							(start 0.1778 0.2794)
							(mid 0.249642 0.249642)
							(end 0.2794 0.1778)
						)
						(arc
							(start 0.2794 -0.1778)
							(mid 0.249642 -0.249642)
							(end 0.1778 -0.2794)
						)
					)
					(width 0)
					(fill yes)
				)
			)
		)
	)
)
